(kicad_pcb
	(version 20260206)
	(generator "pcbnew")
	(generator_version "10.0")
	(general
		(thickness 1.6)
		(legacy_teardrops no)
	)
	(paper "A4")
	(title_block
		(title "01162023_DA0F0TEBIF0_F0T_Expander_BD_F_brd_V02_OCP.brd")
		(comment 1 "Grand Teton / footprint 4451 of 9728 (PEX3), pads 714-835 of 2397")
	)
	(layers
		(0 "F.Cu" signal "TOP")
		(4 "In1.Cu" signal "GND")
		(6 "In2.Cu" signal "VCC")
		(8 "In3.Cu" signal "VCC1")
		(10 "In4.Cu" signal "GND1")
		(12 "In5.Cu" signal "IN1")
		(14 "In6.Cu" signal "GND2")
		(16 "In7.Cu" signal "IN2")
		(18 "In8.Cu" signal "GND3")
		(20 "In9.Cu" signal "IN3")
		(22 "In10.Cu" signal "GND4")
		(24 "In11.Cu" signal "IN4")
		(26 "In12.Cu" signal "GND5")
		(28 "In13.Cu" signal "IN5")
		(30 "In14.Cu" signal "GND6")
		(32 "In15.Cu" signal "IN6")
		(34 "In16.Cu" signal "GND7")
		(2 "B.Cu" signal "BOTTOM")
		(9 "F.Adhes" user "F.Adhesive")
		(11 "B.Adhes" user "B.Adhesive")
		(13 "F.Paste" user "Package Geometry/Pastemask Top")
		(15 "B.Paste" user "Package Geometry/Pastemask Bottom")
		(5 "F.SilkS" user "Ref Des/Silkscreen Top")
		(7 "B.SilkS" user "Ref Des/Silkscreen Bottom")
		(1 "F.Mask" user "Board Geometry/Soldermask Top")
		(3 "B.Mask" user "Board Geometry/Soldermask Bottom")
		(17 "Dwgs.User" user "User.Drawings")
		(19 "Cmts.User" user "User.Comments")
		(21 "Eco1.User" user "User.Eco1")
		(23 "Eco2.User" user "User.Eco2")
		(25 "Edge.Cuts" user "Board Geometry/Outline")
		(27 "Margin" user)
		(31 "F.CrtYd" user "Package Geometry/Place Bound Top")
		(29 "B.CrtYd" user "Package Geometry/Place Bound Bottom")
		(35 "F.Fab" user "Ref Des/Assembly Top")
		(33 "B.Fab" user "Ref Des/Assembly Bottom")
	)
	(footprint ""
		(layer "F.Cu")
		(at 407.949908 -295.89984)
		(property "Reference" "PEX3"
			(at -3.358642 35.5727 0)
			(unlocked yes)
			(layer "F.SilkS")
			(effects
				(font
					(size 2.032 1.524)
					(thickness 0.1524)
				)
				(justify left)
			)
		)
		(property "Value" ""
			(at 0 0 0)
			(layer "F.Fab")
			(effects
				(font
					(size 1.27 1.27)
				)
			)
		)
		(duplicate_pad_numbers_are_jumpers no)
		(pad "AP30" smd circle
			(at 4.750054 8.549894)
			(size 0.4572 0.4572)
			(layers "F.Cu" "F.Mask" "F.Paste")
			(net "P1V25_SERDES_VDDPLL_PEX3")
		)
		(pad "AP31" smd circle
			(at 5.700014 8.549894)
			(size 0.4572 0.4572)
			(layers "F.Cu" "F.Mask" "F.Paste")
			(net "P1V25_SERDES_VDDPLL_PEX3")
		)
		(pad "AP32" smd circle
			(at 6.649974 8.549894)
			(size 0.4572 0.4572)
			(layers "F.Cu" "F.Mask" "F.Paste")
			(net "P1V25_SERDES_VDDPLL_PEX3")
		)
		(pad "AP33" smd circle
			(at 7.599934 8.549894)
			(size 0.4572 0.4572)
			(layers "F.Cu" "F.Mask" "F.Paste")
			(net "P1V25_SERDES_VDDPLL_PEX3")
		)
		(pad "AP34" smd circle
			(at 8.549894 8.549894)
			(size 0.4572 0.4572)
			(layers "F.Cu" "F.Mask" "F.Paste")
			(net "GND")
		)
		(pad "AP35" smd circle
			(at 9.500108 8.549894)
			(size 0.4572 0.4572)
			(layers "F.Cu" "F.Mask" "F.Paste")
			(net "P1V8_VDDA_PEX3")
		)
		(pad "AP36" smd circle
			(at 10.450068 8.549894)
			(size 0.4572 0.4572)
			(layers "F.Cu" "F.Mask" "F.Paste")
			(net "Net_536")
		)
		(pad "AP37" smd circle
			(at 11.400028 8.549894)
			(size 0.4572 0.4572)
			(layers "F.Cu" "F.Mask" "F.Paste")
			(net "GND")
		)
		(pad "AP38" smd circle
			(at 12.349988 8.549894)
			(size 0.4572 0.4572)
			(layers "F.Cu" "F.Mask" "F.Paste")
			(net "Net_5470")
		)
		(pad "AP39" smd circle
			(at 13.299948 8.549894)
			(size 0.4572 0.4572)
			(layers "F.Cu" "F.Mask" "F.Paste")
			(net "Net_5476")
		)
		(pad "AP40" smd circle
			(at 14.249908 8.549894)
			(size 0.4572 0.4572)
			(layers "F.Cu" "F.Mask" "F.Paste")
			(net "GND")
		)
		(pad "AP41" smd circle
			(at 15.200122 8.549894)
			(size 0.4572 0.4572)
			(layers "F.Cu" "F.Mask" "F.Paste")
			(net "P5E_PEX3_STN0_TX_DP<1>")
		)
		(pad "AP42" smd circle
			(at 16.150082 8.549894)
			(size 0.4572 0.4572)
			(layers "F.Cu" "F.Mask" "F.Paste")
			(net "P5E_PEX3_STN0_TX_DN<1>")
		)
		(pad "AP43" smd circle
			(at 17.100042 8.549894)
			(size 0.4572 0.4572)
			(layers "F.Cu" "F.Mask" "F.Paste")
			(net "GND")
		)
		(pad "AP44" smd circle
			(at 18.050002 8.549894)
			(size 0.4572 0.4572)
			(layers "F.Cu" "F.Mask" "F.Paste")
			(net "GND")
		)
		(pad "AP45" smd circle
			(at 18.999962 8.549894)
			(size 0.4572 0.4572)
			(layers "F.Cu" "F.Mask" "F.Paste")
			(net "GND")
		)
		(pad "AP46" smd circle
			(at 19.949922 8.549894)
			(size 0.4572 0.4572)
			(layers "F.Cu" "F.Mask" "F.Paste")
			(net "GND")
		)
		(pad "AP47" smd circle
			(at 20.899882 8.549894)
			(size 0.4572 0.4572)
			(layers "F.Cu" "F.Mask" "F.Paste")
			(net "GND")
		)
		(pad "AP48" smd circle
			(at 21.850096 8.549894)
			(size 0.4572 0.4572)
			(layers "F.Cu" "F.Mask" "F.Paste")
			(net "P5E_PEX3_STN0_RX_DP<1>")
		)
		(pad "AP49" smd circle
			(at 22.800056 8.549894)
			(size 0.4572 0.4572)
			(layers "F.Cu" "F.Mask" "F.Paste")
			(net "P5E_PEX3_STN0_RX_DN<1>")
		)
		(pad "AR1" smd circle
			(at -22.800056 9.500108)
			(size 0.4572 0.4572)
			(layers "F.Cu" "F.Mask" "F.Paste")
			(net "GND")
		)
		(pad "AR2" smd circle
			(at -21.850096 9.500108)
			(size 0.4572 0.4572)
			(layers "F.Cu" "F.Mask" "F.Paste")
			(net "GND")
		)
		(pad "AR3" smd circle
			(at -20.899882 9.500108)
			(size 0.4572 0.4572)
			(layers "F.Cu" "F.Mask" "F.Paste")
			(net "Net_1487")
		)
		(pad "AR4" smd circle
			(at -19.949922 9.500108)
			(size 0.4572 0.4572)
			(layers "F.Cu" "F.Mask" "F.Paste")
			(net "Net_1502")
		)
		(pad "AR5" smd circle
			(at -18.999962 9.500108)
			(size 0.4572 0.4572)
			(layers "F.Cu" "F.Mask" "F.Paste")
			(net "GND")
		)
		(pad "AR6" smd circle
			(at -18.050002 9.500108)
			(size 0.4572 0.4572)
			(layers "F.Cu" "F.Mask" "F.Paste")
			(net "Net_1484")
		)
		(pad "AR7" smd circle
			(at -17.100042 9.500108)
			(size 0.4572 0.4572)
			(layers "F.Cu" "F.Mask" "F.Paste")
			(net "Net_1390")
		)
		(pad "AR8" smd circle
			(at -16.150082 9.500108)
			(size 0.4572 0.4572)
			(layers "F.Cu" "F.Mask" "F.Paste")
			(net "GND")
		)
		(pad "AR9" smd circle
			(at -15.200122 9.500108)
			(size 0.4572 0.4572)
			(layers "F.Cu" "F.Mask" "F.Paste")
			(net "GND")
		)
		(pad "AR10" smd circle
			(at -14.249908 9.500108)
			(size 0.4572 0.4572)
			(layers "F.Cu" "F.Mask" "F.Paste")
			(net "GND")
		)
		(pad "AR11" smd circle
			(at -13.299948 9.500108)
			(size 0.4572 0.4572)
			(layers "F.Cu" "F.Mask" "F.Paste")
			(net "GND")
		)
		(pad "AR12" smd circle
			(at -12.349988 9.500108)
			(size 0.4572 0.4572)
			(layers "F.Cu" "F.Mask" "F.Paste")
			(net "GND")
		)
		(pad "AR13" smd circle
			(at -11.400028 9.500108)
			(size 0.4572 0.4572)
			(layers "F.Cu" "F.Mask" "F.Paste")
			(net "GND")
		)
		(pad "AR14" smd circle
			(at -10.450068 9.500108)
			(size 0.4572 0.4572)
			(layers "F.Cu" "F.Mask" "F.Paste")
			(net "GND")
		)
		(pad "AR15" smd circle
			(at -9.500108 9.500108)
			(size 0.4572 0.4572)
			(layers "F.Cu" "F.Mask" "F.Paste")
			(net "GND")
		)
		(pad "AR16" smd circle
			(at -8.549894 9.500108)
			(size 0.4572 0.4572)
			(layers "F.Cu" "F.Mask" "F.Paste")
			(net "GND")
		)
		(pad "AR17" smd circle
			(at -7.599934 9.500108)
			(size 0.4572 0.4572)
			(layers "F.Cu" "F.Mask" "F.Paste")
			(net "GND")
		)
		(pad "AR18" smd circle
			(at -6.649974 9.500108)
			(size 0.4572 0.4572)
			(layers "F.Cu" "F.Mask" "F.Paste")
			(net "GND")
		)
		(pad "AR19" smd circle
			(at -5.700014 9.500108)
			(size 0.4572 0.4572)
			(layers "F.Cu" "F.Mask" "F.Paste")
			(net "GND")
		)
		(pad "AR20" smd circle
			(at -4.750054 9.500108)
			(size 0.4572 0.4572)
			(layers "F.Cu" "F.Mask" "F.Paste")
			(net "GND")
		)
		(pad "AR21" smd circle
			(at -3.800094 9.500108)
			(size 0.4572 0.4572)
			(layers "F.Cu" "F.Mask" "F.Paste")
			(net "GND")
		)
		(pad "AR22" smd circle
			(at -2.84988 9.500108)
			(size 0.4572 0.4572)
			(layers "F.Cu" "F.Mask" "F.Paste")
			(net "GND")
		)
		(pad "AR23" smd circle
			(at -1.89992 9.500108)
			(size 0.4572 0.4572)
			(layers "F.Cu" "F.Mask" "F.Paste")
			(net "GND")
		)
		(pad "AR24" smd circle
			(at -0.94996 9.500108)
			(size 0.4572 0.4572)
			(layers "F.Cu" "F.Mask" "F.Paste")
			(net "GND")
		)
		(pad "AR25" smd circle
			(at 0 9.500108)
			(size 0.4572 0.4572)
			(layers "F.Cu" "F.Mask" "F.Paste")
			(net "GND")
		)
		(pad "AR26" smd circle
			(at 0.94996 9.500108)
			(size 0.4572 0.4572)
			(layers "F.Cu" "F.Mask" "F.Paste")
			(net "GND")
		)
		(pad "AR27" smd circle
			(at 1.89992 9.500108)
			(size 0.4572 0.4572)
			(layers "F.Cu" "F.Mask" "F.Paste")
			(net "GND")
		)
		(pad "AR28" smd circle
			(at 2.84988 9.500108)
			(size 0.4572 0.4572)
			(layers "F.Cu" "F.Mask" "F.Paste")
			(net "GND")
		)
		(pad "AR29" smd circle
			(at 3.800094 9.500108)
			(size 0.4572 0.4572)
			(layers "F.Cu" "F.Mask" "F.Paste")
			(net "GND")
		)
		(pad "AR30" smd circle
			(at 4.750054 9.500108)
			(size 0.4572 0.4572)
			(layers "F.Cu" "F.Mask" "F.Paste")
			(net "GND")
		)
		(pad "AR31" smd circle
			(at 5.700014 9.500108)
			(size 0.4572 0.4572)
			(layers "F.Cu" "F.Mask" "F.Paste")
			(net "GND")
		)
		(pad "AR32" smd circle
			(at 6.649974 9.500108)
			(size 0.4572 0.4572)
			(layers "F.Cu" "F.Mask" "F.Paste")
			(net "GND")
		)
		(pad "AR33" smd circle
			(at 7.599934 9.500108)
			(size 0.4572 0.4572)
			(layers "F.Cu" "F.Mask" "F.Paste")
			(net "GND")
		)
		(pad "AR34" smd circle
			(at 8.549894 9.500108)
			(size 0.4572 0.4572)
			(layers "F.Cu" "F.Mask" "F.Paste")
			(net "GND")
		)
		(pad "AR35" smd circle
			(at 9.500108 9.500108)
			(size 0.4572 0.4572)
			(layers "F.Cu" "F.Mask" "F.Paste")
			(net "GND")
		)
		(pad "AR36" smd circle
			(at 10.450068 9.500108)
			(size 0.4572 0.4572)
			(layers "F.Cu" "F.Mask" "F.Paste")
			(net "Net_531")
		)
		(pad "AR37" smd circle
			(at 11.400028 9.500108)
			(size 0.4572 0.4572)
			(layers "F.Cu" "F.Mask" "F.Paste")
			(net "GND")
		)
		(pad "AR38" smd circle
			(at 12.349988 9.500108)
			(size 0.4572 0.4572)
			(layers "F.Cu" "F.Mask" "F.Paste")
			(net "Net_5475")
		)
		(pad "AR39" smd circle
			(at 13.299948 9.500108)
			(size 0.4572 0.4572)
			(layers "F.Cu" "F.Mask" "F.Paste")
			(net "Net_5477")
		)
		(pad "AR40" smd circle
			(at 14.249908 9.500108)
			(size 0.4572 0.4572)
			(layers "F.Cu" "F.Mask" "F.Paste")
			(net "GND")
		)
		(pad "AR41" smd circle
			(at 15.200122 9.500108)
			(size 0.4572 0.4572)
			(layers "F.Cu" "F.Mask" "F.Paste")
			(net "GND")
		)
		(pad "AR42" smd circle
			(at 16.150082 9.500108)
			(size 0.4572 0.4572)
			(layers "F.Cu" "F.Mask" "F.Paste")
			(net "GND")
		)
		(pad "AR43" smd circle
			(at 17.100042 9.500108)
			(size 0.4572 0.4572)
			(layers "F.Cu" "F.Mask" "F.Paste")
			(net "P5E_PEX3_STN0_TX_DP<2>")
		)
		(pad "AR44" smd circle
			(at 18.050002 9.500108)
			(size 0.4572 0.4572)
			(layers "F.Cu" "F.Mask" "F.Paste")
			(net "P5E_PEX3_STN0_TX_DN<2>")
		)
		(pad "AR45" smd circle
			(at 18.999962 9.500108)
			(size 0.4572 0.4572)
			(layers "F.Cu" "F.Mask" "F.Paste")
			(net "GND")
		)
		(pad "AR46" smd circle
			(at 19.949922 9.500108)
			(size 0.4572 0.4572)
			(layers "F.Cu" "F.Mask" "F.Paste")
			(net "P5E_PEX3_STN0_RX_DP<2>")
		)
		(pad "AR47" smd circle
			(at 20.899882 9.500108)
			(size 0.4572 0.4572)
			(layers "F.Cu" "F.Mask" "F.Paste")
			(net "P5E_PEX3_STN0_RX_DN<2>")
		)
		(pad "AR48" smd circle
			(at 21.850096 9.500108)
			(size 0.4572 0.4572)
			(layers "F.Cu" "F.Mask" "F.Paste")
			(net "GND")
		)
		(pad "AR49" smd circle
			(at 22.800056 9.500108)
			(size 0.4572 0.4572)
			(layers "F.Cu" "F.Mask" "F.Paste")
			(net "GND")
		)
		(pad "AT1" smd circle
			(at -22.800056 10.450068)
			(size 0.4572 0.4572)
			(layers "F.Cu" "F.Mask" "F.Paste")
			(net "Net_1491")
		)
		(pad "AT2" smd circle
			(at -21.850096 10.450068)
			(size 0.4572 0.4572)
			(layers "F.Cu" "F.Mask" "F.Paste")
			(net "Net_1495")
		)
		(pad "AT3" smd circle
			(at -20.899882 10.450068)
			(size 0.4572 0.4572)
			(layers "F.Cu" "F.Mask" "F.Paste")
			(net "GND")
		)
		(pad "AT4" smd circle
			(at -19.949922 10.450068)
			(size 0.4572 0.4572)
			(layers "F.Cu" "F.Mask" "F.Paste")
			(net "GND")
		)
		(pad "AT5" smd circle
			(at -18.999962 10.450068)
			(size 0.4572 0.4572)
			(layers "F.Cu" "F.Mask" "F.Paste")
			(net "GND")
		)
		(pad "AT6" smd circle
			(at -18.050002 10.450068)
			(size 0.4572 0.4572)
			(layers "F.Cu" "F.Mask" "F.Paste")
			(net "GND")
		)
		(pad "AT7" smd circle
			(at -17.100042 10.450068)
			(size 0.4572 0.4572)
			(layers "F.Cu" "F.Mask" "F.Paste")
			(net "GND")
		)
		(pad "AT8" smd circle
			(at -16.150082 10.450068)
			(size 0.4572 0.4572)
			(layers "F.Cu" "F.Mask" "F.Paste")
			(net "Net_1367")
		)
		(pad "AT9" smd circle
			(at -15.200122 10.450068)
			(size 0.4572 0.4572)
			(layers "F.Cu" "F.Mask" "F.Paste")
			(net "Net_1468")
		)
		(pad "AT10" smd circle
			(at -14.249908 10.450068)
			(size 0.4572 0.4572)
			(layers "F.Cu" "F.Mask" "F.Paste")
			(net "GND")
		)
		(pad "AT11" smd circle
			(at -13.299948 10.450068)
			(size 0.4572 0.4572)
			(layers "F.Cu" "F.Mask" "F.Paste")
			(net "GND")
		)
		(pad "AT12" smd circle
			(at -12.349988 10.450068)
			(size 0.4572 0.4572)
			(layers "F.Cu" "F.Mask" "F.Paste")
			(net "GND")
		)
		(pad "AT13" smd circle
			(at -11.400028 10.450068)
			(size 0.4572 0.4572)
			(layers "F.Cu" "F.Mask" "F.Paste")
			(net "GND")
		)
		(pad "AT14" smd circle
			(at -10.450068 10.450068)
			(size 0.4572 0.4572)
			(layers "F.Cu" "F.Mask" "F.Paste")
			(net "GND")
		)
		(pad "AT15" smd circle
			(at -9.500108 10.450068)
			(size 0.4572 0.4572)
			(layers "F.Cu" "F.Mask" "F.Paste")
			(net "GND")
		)
		(pad "AT16" smd circle
			(at -8.549894 10.450068)
			(size 0.4572 0.4572)
			(layers "F.Cu" "F.Mask" "F.Paste")
			(net "GND")
		)
		(pad "AT17" smd circle
			(at -7.599934 10.450068)
			(size 0.4572 0.4572)
			(layers "F.Cu" "F.Mask" "F.Paste")
			(net "GND")
		)
		(pad "AT18" smd circle
			(at -6.649974 10.450068)
			(size 0.4572 0.4572)
			(layers "F.Cu" "F.Mask" "F.Paste")
			(net "GND")
		)
		(pad "AT19" smd circle
			(at -5.700014 10.450068)
			(size 0.4572 0.4572)
			(layers "F.Cu" "F.Mask" "F.Paste")
			(net "GND")
		)
		(pad "AT20" smd circle
			(at -4.750054 10.450068)
			(size 0.4572 0.4572)
			(layers "F.Cu" "F.Mask" "F.Paste")
			(net "GND")
		)
		(pad "AT21" smd circle
			(at -3.800094 10.450068)
			(size 0.4572 0.4572)
			(layers "F.Cu" "F.Mask" "F.Paste")
			(net "GND")
		)
		(pad "AT22" smd circle
			(at -2.84988 10.450068)
			(size 0.4572 0.4572)
			(layers "F.Cu" "F.Mask" "F.Paste")
			(net "GND")
		)
		(pad "AT23" smd circle
			(at -1.89992 10.450068)
			(size 0.4572 0.4572)
			(layers "F.Cu" "F.Mask" "F.Paste")
			(net "GND")
		)
		(pad "AT24" smd circle
			(at -0.94996 10.450068)
			(size 0.4572 0.4572)
			(layers "F.Cu" "F.Mask" "F.Paste")
			(net "GND")
		)
		(pad "AT25" smd circle
			(at 0 10.450068)
			(size 0.4572 0.4572)
			(layers "F.Cu" "F.Mask" "F.Paste")
			(net "GND")
		)
		(pad "AT26" smd circle
			(at 0.94996 10.450068)
			(size 0.4572 0.4572)
			(layers "F.Cu" "F.Mask" "F.Paste")
			(net "GND")
		)
		(pad "AT27" smd circle
			(at 1.89992 10.450068)
			(size 0.4572 0.4572)
			(layers "F.Cu" "F.Mask" "F.Paste")
			(net "GND")
		)
		(pad "AT28" smd circle
			(at 2.84988 10.450068)
			(size 0.4572 0.4572)
			(layers "F.Cu" "F.Mask" "F.Paste")
			(net "GND")
		)
		(pad "AT29" smd circle
			(at 3.800094 10.450068)
			(size 0.4572 0.4572)
			(layers "F.Cu" "F.Mask" "F.Paste")
			(net "GND")
		)
		(pad "AT30" smd circle
			(at 4.750054 10.450068)
			(size 0.4572 0.4572)
			(layers "F.Cu" "F.Mask" "F.Paste")
			(net "GND")
		)
		(pad "AT31" smd circle
			(at 5.700014 10.450068)
			(size 0.4572 0.4572)
			(layers "F.Cu" "F.Mask" "F.Paste")
			(net "GND")
		)
		(pad "AT32" smd circle
			(at 6.649974 10.450068)
			(size 0.4572 0.4572)
			(layers "F.Cu" "F.Mask" "F.Paste")
			(net "GND")
		)
		(pad "AT33" smd circle
			(at 7.599934 10.450068)
			(size 0.4572 0.4572)
			(layers "F.Cu" "F.Mask" "F.Paste")
			(net "GND")
		)
		(pad "AT34" smd circle
			(at 8.549894 10.450068)
			(size 0.4572 0.4572)
			(layers "F.Cu" "F.Mask" "F.Paste")
			(net "GND")
		)
		(pad "AT35" smd circle
			(at 9.500108 10.450068)
			(size 0.4572 0.4572)
			(layers "F.Cu" "F.Mask" "F.Paste")
			(net "GND")
		)
		(pad "AT36" smd circle
			(at 10.450068 10.450068)
			(size 0.4572 0.4572)
			(layers "F.Cu" "F.Mask" "F.Paste")
			(net "Net_541")
		)
		(pad "AT37" smd circle
			(at 11.400028 10.450068)
			(size 0.4572 0.4572)
			(layers "F.Cu" "F.Mask" "F.Paste")
			(net "GND")
		)
		(pad "AT38" smd circle
			(at 12.349988 10.450068)
			(size 0.4572 0.4572)
			(layers "F.Cu" "F.Mask" "F.Paste")
			(net "Net_5441")
		)
		(pad "AT39" smd circle
			(at 13.299948 10.450068)
			(size 0.4572 0.4572)
			(layers "F.Cu" "F.Mask" "F.Paste")
			(net "Net_5426")
		)
		(pad "AT40" smd circle
			(at 14.249908 10.450068)
			(size 0.4572 0.4572)
			(layers "F.Cu" "F.Mask" "F.Paste")
			(net "GND")
		)
		(pad "AT41" smd circle
			(at 15.200122 10.450068)
			(size 0.4572 0.4572)
			(layers "F.Cu" "F.Mask" "F.Paste")
			(net "P5E_PEX3_STN0_TX_DP<3>")
		)
		(pad "AT42" smd circle
			(at 16.150082 10.450068)
			(size 0.4572 0.4572)
			(layers "F.Cu" "F.Mask" "F.Paste")
			(net "P5E_PEX3_STN0_TX_DN<3>")
		)
		(pad "AT43" smd circle
			(at 17.100042 10.450068)
			(size 0.4572 0.4572)
			(layers "F.Cu" "F.Mask" "F.Paste")
			(net "GND")
		)
		(pad "AT44" smd circle
			(at 18.050002 10.450068)
			(size 0.4572 0.4572)
			(layers "F.Cu" "F.Mask" "F.Paste")
			(net "GND")
		)
		(pad "AT45" smd circle
			(at 18.999962 10.450068)
			(size 0.4572 0.4572)
			(layers "F.Cu" "F.Mask" "F.Paste")
			(net "GND")
		)
		(pad "AT46" smd circle
			(at 19.949922 10.450068)
			(size 0.4572 0.4572)
			(layers "F.Cu" "F.Mask" "F.Paste")
			(net "GND")
		)
		(pad "AT47" smd circle
			(at 20.899882 10.450068)
			(size 0.4572 0.4572)
			(layers "F.Cu" "F.Mask" "F.Paste")
			(net "GND")
		)
		(pad "AT48" smd circle
			(at 21.850096 10.450068)
			(size 0.4572 0.4572)
			(layers "F.Cu" "F.Mask" "F.Paste")
			(net "P5E_PEX3_STN0_RX_DP<3>")
		)
		(pad "AT49" smd circle
			(at 22.800056 10.450068)
			(size 0.4572 0.4572)
			(layers "F.Cu" "F.Mask" "F.Paste")
			(net "P5E_PEX3_STN0_RX_DN<3>")
		)
		(pad "AU1" smd circle
			(at -22.800056 11.400028)
			(size 0.4572 0.4572)
			(layers "F.Cu" "F.Mask" "F.Paste")
			(net "GND")
		)
		(pad "AU2" smd circle
			(at -21.850096 11.400028)
			(size 0.4572 0.4572)
			(layers "F.Cu" "F.Mask" "F.Paste")
			(net "GND")
		)
		(pad "AU3" smd circle
			(at -20.899882 11.400028)
			(size 0.4572 0.4572)
			(layers "F.Cu" "F.Mask" "F.Paste")
			(net "Net_1482")
		)
		(pad "AU4" smd circle
			(at -19.949922 11.400028)
			(size 0.4572 0.4572)
			(layers "F.Cu" "F.Mask" "F.Paste")
			(net "Net_1430")
		)
	)
)
